# BASEBOARD_FAB2 (Tioga Pass) — schematic netlist excerpt (pin names and nets, part order shuffled) for the footprints in the layout excerpt that follows; sources: Cadence DE-HDL packaged netlist, KiCad conversion of Wiwynn_Tioga_Pass_MB.brd

R1D28  RES  100.0 1% EMPTY  pkg 0402  page 199 : A = PD_HSC_RETRY_N ; B = AGND_HSC
C7D3  CAP_A  22.0UF 4V 20% X6S  pkg 0603V  page 130 : A = P1V8_PCH_STBY ; B = GND
R1U56  RES  0.0 5% EMPTY  pkg 0402  page 152 : A = H_CPU0_MEMDEF_MEMHOT_G_PCH_N ; B = H_CPU0_MEMDEF_MEMHOT_G_N

(kicad_pcb
	(version 20260206)
	(generator "pcbnew")
	(generator_version "10.0")
	(general
		(thickness 1.6)
		(legacy_teardrops no)
	)
	(paper "A4")
	(title_block
		(title "Wiwynn_Tioga_Pass_MB.brd")
		(comment 1 "Tioga Pass / footprints 1469-1471 of 4770")
	)
	(layers
		(0 "F.Cu" signal "TOP")
		(4 "In1.Cu" signal "L2GND")
		(6 "In2.Cu" signal "L3")
		(8 "In3.Cu" signal "L4GND")
		(10 "In4.Cu" signal "L5")
		(12 "In5.Cu" signal "L6GND")
		(14 "In6.Cu" signal "L7VCC")
		(16 "In7.Cu" signal "L8VCC")
		(18 "In8.Cu" signal "L9GND")
		(20 "In9.Cu" signal "L10")
		(22 "In10.Cu" signal "L11GND")
		(24 "In11.Cu" signal "L12")
		(26 "In12.Cu" signal "L13GND")
		(2 "B.Cu" signal "BOTTOM")
		(9 "F.Adhes" user "F.Adhesive")
		(11 "B.Adhes" user "B.Adhesive")
		(13 "F.Paste" user "Package Geometry/Pastemask Top")
		(15 "B.Paste" user "Package Geometry/Pastemask Bottom")
		(5 "F.SilkS" user "Ref Des/Silkscreen Top")
		(7 "B.SilkS" user "Ref Des/Silkscreen Bottom")
		(1 "F.Mask" user "Board Geometry/Soldermask Top")
		(3 "B.Mask" user "Board Geometry/Soldermask Bottom")
		(17 "Dwgs.User" user "User.Drawings")
		(19 "Cmts.User" user "User.Comments")
		(21 "Eco1.User" user "User.Eco1")
		(23 "Eco2.User" user "User.Eco2")
		(25 "Edge.Cuts" user "Board Geometry/Outline")
		(27 "Margin" user)
		(31 "F.CrtYd" user "Package Geometry/Place Bound Top")
		(29 "B.CrtYd" user "Package Geometry/Place Bound Bottom")
		(35 "F.Fab" user "Ref Des/Assembly Top")
		(33 "B.Fab" user "Ref Des/Assembly Bottom")
	)
	(footprint ""
		(layer "F.Cu")
		(at 403.6314 -128.3335)
		(property "Reference" "C7D3"
			(at 0 0 0)
			(layer "F.SilkS")
			(hide yes)
			(effects
				(font
					(size 1.27 1.27)
				)
			)
		)
		(property "Value" ""
			(at 0 0 0)
			(layer "F.Fab")
			(effects
				(font
					(size 1.27 1.27)
				)
			)
		)
		(duplicate_pad_numbers_are_jumpers no)
		(fp_poly
			(pts
				(xy -0.4953 -0.2032) (xy 0.4953 -0.2032) (xy 0.4953 1.6002) (xy -0.4953 1.6002)
			)
			(stroke
				(width 0)
				(type default)
			)
			(fill no)
			(layer "F.CrtYd")
		)
		(fp_line
			(start -0.4953 -0.2032)
			(end 0.4953 -0.2032)
			(stroke
				(width 0.1)
				(type default)
			)
			(layer "F.Fab")
		)
		(fp_line
			(start -0.4953 1.6002)
			(end -0.4953 -0.2032)
			(stroke
				(width 0.1)
				(type default)
			)
			(layer "F.Fab")
		)
		(fp_line
			(start 0.4953 -0.2032)
			(end 0.4953 1.6002)
			(stroke
				(width 0.1)
				(type default)
			)
			(layer "F.Fab")
		)
		(fp_line
			(start 0.4953 1.6002)
			(end -0.4953 1.6002)
			(stroke
				(width 0.1)
				(type default)
			)
			(layer "F.Fab")
		)
		(pad "1" smd rect
			(at 0 0)
			(size 0.762 0.889)
			(layers "F.Cu" "F.Mask" "F.Paste")
			(net "P1V8_PCH_STBY")
		)
		(pad "2" smd rect
			(at 0 1.397)
			(size 0.762 0.889)
			(layers "F.Cu" "F.Mask" "F.Paste")
			(net "GND")
		)
		(zone
			(layer "F.Cu")
			(hatch none 0.5)
			(connect_pads
				(clearance 0)
			)
			(min_thickness 0.25)
			(keepout
				(tracks not_allowed)
				(vias allowed)
				(pads allowed)
				(copperpour not_allowed)
				(footprints allowed)
			)
			(placement
				(enabled no)
				(sheetname "")
			)
			(fill
				(thermal_gap 0.5)
				(thermal_bridge_width 0.5)
				(island_removal_mode 0)
			)
			(polygon
				(pts
					(xy 403.2504 -127.889) (xy 404.0124 -127.889) (xy 404.0124 -127.381) (xy 403.2504 -127.381)
				)
			)
		)
	)
	(footprint ""
		(layer "F.Cu")
		(at 14.097 -79.4385 180)
		(property "Reference" "R1D28"
			(at 0 0 180)
			(layer "F.SilkS")
			(hide yes)
			(effects
				(font
					(size 1.27 1.27)
				)
			)
		)
		(property "Value" ""
			(at 0 0 180)
			(layer "F.Fab")
			(effects
				(font
					(size 1.27 1.27)
				)
			)
		)
		(duplicate_pad_numbers_are_jumpers no)
		(fp_poly
			(pts
				(xy -0.2794 -0.1016) (xy 0.2794 -0.1016) (xy 0.2794 0.9906) (xy -0.2794 0.9906)
			)
			(stroke
				(width 0)
				(type default)
			)
			(fill no)
			(layer "F.CrtYd")
		)
		(fp_line
			(start 0.2794 0.9906)
			(end 0.2794 -0.1016)
			(stroke
				(width 0.1)
				(type default)
			)
			(layer "F.Fab")
		)
		(fp_line
			(start 0.2794 -0.1016)
			(end -0.2794 -0.1016)
			(stroke
				(width 0.1)
				(type default)
			)
			(layer "F.Fab")
		)
		(fp_line
			(start -0.2794 0.9906)
			(end 0.2794 0.9906)
			(stroke
				(width 0.1)
				(type default)
			)
			(layer "F.Fab")
		)
		(fp_line
			(start -0.2794 -0.1016)
			(end -0.2794 0.9906)
			(stroke
				(width 0.1)
				(type default)
			)
			(layer "F.Fab")
		)
		(pad "1" smd rect
			(at 0 0 180)
			(size 0.508 0.508)
			(layers "F.Cu" "F.Mask" "F.Paste")
			(net "PD_HSC_RETRY_N")
		)
		(pad "2" smd rect
			(at 0 0.889 180)
			(size 0.508 0.508)
			(layers "F.Cu" "F.Mask" "F.Paste")
			(net "AGND_HSC")
		)
		(zone
			(layer "F.Cu")
			(hatch none 0.5)
			(connect_pads
				(clearance 0)
			)
			(min_thickness 0.25)
			(keepout
				(tracks not_allowed)
				(vias allowed)
				(pads allowed)
				(copperpour not_allowed)
				(footprints allowed)
			)
			(placement
				(enabled no)
				(sheetname "")
			)
			(fill
				(thermal_gap 0.5)
				(thermal_bridge_width 0.5)
				(island_removal_mode 0)
			)
			(polygon
				(pts
					(xy 14.351 -80.0735) (xy 13.843 -80.0735) (xy 13.843 -79.6925) (xy 14.351 -79.6925)
				)
			)
		)
		(zone
			(layer "F.Cu")
			(hatch none 0.5)
			(connect_pads
				(clearance 0)
			)
			(min_thickness 0.25)
			(keepout
				(tracks allowed)
				(vias not_allowed)
				(pads allowed)
				(copperpour not_allowed)
				(footprints allowed)
			)
			(placement
				(enabled no)
				(sheetname "")
			)
			(fill
				(thermal_gap 0.5)
				(thermal_bridge_width 0.5)
				(island_removal_mode 0)
			)
			(polygon
				(pts
					(xy 14.351 -79.6925) (xy 13.843 -79.6925) (xy 13.843 -80.0735) (xy 14.351 -80.0735)
				)
			)
		)
	)
	(footprint ""
		(layer "F.Cu")
		(at 438.531 -12.954 180)
		(property "Reference" "R1U56"
			(at 0 0 180)
			(layer "F.SilkS")
			(hide yes)
			(effects
				(font
					(size 1.27 1.27)
				)
			)
		)
		(property "Value" ""
			(at 0 0 180)
			(layer "F.Fab")
			(effects
				(font
					(size 1.27 1.27)
				)
			)
		)
		(duplicate_pad_numbers_are_jumpers no)
		(fp_poly
			(pts
				(xy -0.2794 -0.1016) (xy 0.2794 -0.1016) (xy 0.2794 0.9906) (xy -0.2794 0.9906)
			)
			(stroke
				(width 0)
				(type default)
			)
			(fill no)
			(layer "F.CrtYd")
		)
		(fp_line
			(start 0.2794 0.9906)
			(end 0.2794 -0.1016)
			(stroke
				(width 0.1)
				(type default)
			)
			(layer "F.Fab")
		)
		(fp_line
			(start 0.2794 -0.1016)
			(end -0.2794 -0.1016)
			(stroke
				(width 0.1)
				(type default)
			)
			(layer "F.Fab")
		)
		(fp_line
			(start -0.2794 0.9906)
			(end 0.2794 0.9906)
			(stroke
				(width 0.1)
				(type default)
			)
			(layer "F.Fab")
		)
		(fp_line
			(start -0.2794 -0.1016)
			(end -0.2794 0.9906)
			(stroke
				(width 0.1)
				(type default)
			)
			(layer "F.Fab")
		)
		(pad "1" smd rect
			(at 0 0 180)
			(size 0.508 0.508)
			(layers "F.Cu" "F.Mask" "F.Paste")
			(net "H_CPU0_MEMDEF_MEMHOT_G_PCH_N")
		)
		(pad "2" smd rect
			(at 0 0.889 180)
			(size 0.508 0.508)
			(layers "F.Cu" "F.Mask" "F.Paste")
			(net "H_CPU0_MEMDEF_MEMHOT_G_N")
		)
		(zone
			(layer "F.Cu")
			(hatch none 0.5)
			(connect_pads
				(clearance 0)
			)
			(min_thickness 0.25)
			(keepout
				(tracks not_allowed)
				(vias allowed)
				(pads allowed)
				(copperpour not_allowed)
				(footprints allowed)
			)
			(placement
				(enabled no)
				(sheetname "")
			)
			(fill
				(thermal_gap 0.5)
				(thermal_bridge_width 0.5)
				(island_removal_mode 0)
			)
			(polygon
				(pts
					(xy 438.785 -13.589) (xy 438.277 -13.589) (xy 438.277 -13.208) (xy 438.785 -13.208)
				)
			)
		)
		(zone
			(layer "F.Cu")
			(hatch none 0.5)
			(connect_pads
				(clearance 0)
			)
			(min_thickness 0.25)
			(keepout
				(tracks allowed)
				(vias not_allowed)
				(pads allowed)
				(copperpour not_allowed)
				(footprints allowed)
			)
			(placement
				(enabled no)
				(sheetname "")
			)
			(fill
				(thermal_gap 0.5)
				(thermal_bridge_width 0.5)
				(island_removal_mode 0)
			)
			(polygon
				(pts
					(xy 438.785 -13.208) (xy 438.277 -13.208) (xy 438.277 -13.589) (xy 438.785 -13.589)
				)
			)
		)
	)
)
